# SCM (Grand Teton) — schematic netlist excerpt (pin names and nets, part order shuffled) for the footprints in the layout excerpt that follows; sources: Cadence DE-HDL packaged netlist, KiCad conversion of 12092022_DA0F0TMDCD0_F0T_Management_Board_D_brd_V3_OCP.brd

J14  CONN8_TSW10407FD  CONN8_TSW-104-07-F-D EMPTY  pkg HEADER2X4XF  page 26
  \1\  = P3V3_AUX
  \2\  = SMB_TMP421_BMC_MM2_SDA
  \3\  = TMC75_A0
  \4\  = SMB_TMP421_BMC_MM2_SCL
  \5\  = TMC75_A1
  \6\  = SMB_BMC_ALERT16_R_N
  \7\  = TMC75_A2
  \8\  = GND

(kicad_pcb
	(version 20260206)
	(generator "pcbnew")
	(generator_version "10.0")
	(general
		(thickness 1.6)
		(legacy_teardrops no)
	)
	(paper "A4")
	(title_block
		(title "12092022_DA0F0TMDCD0_F0T_Management_Board_D_brd_V3_OCP.brd")
		(comment 1 "Grand Teton / footprints 210-210 of 1440")
	)
	(layers
		(0 "F.Cu" signal "TOP")
		(4 "In1.Cu" signal "GND")
		(6 "In2.Cu" signal "IN1")
		(8 "In3.Cu" signal "GND1")
		(10 "In4.Cu" signal "IN2")
		(12 "In5.Cu" signal "VCC")
		(14 "In6.Cu" signal "VCC1")
		(16 "In7.Cu" signal "IN3")
		(18 "In8.Cu" signal "GND2")
		(20 "In9.Cu" signal "IN4")
		(22 "In10.Cu" signal "GND3")
		(2 "B.Cu" signal "BOTTOM")
		(9 "F.Adhes" user "F.Adhesive")
		(11 "B.Adhes" user "B.Adhesive")
		(13 "F.Paste" user "Package Geometry/Pastemask Top")
		(15 "B.Paste" user "Package Geometry/Pastemask Bottom")
		(5 "F.SilkS" user "Ref Des/Silkscreen Top")
		(7 "B.SilkS" user "Ref Des/Silkscreen Bottom")
		(1 "F.Mask" user "Board Geometry/Soldermask Top")
		(3 "B.Mask" user "Board Geometry/Soldermask Bottom")
		(17 "Dwgs.User" user "User.Drawings")
		(19 "Cmts.User" user "User.Comments")
		(21 "Eco1.User" user "User.Eco1")
		(23 "Eco2.User" user "User.Eco2")
		(25 "Edge.Cuts" user "Board Geometry/Outline")
		(27 "Margin" user)
		(31 "F.CrtYd" user "Package Geometry/Place Bound Top")
		(29 "B.CrtYd" user "Package Geometry/Place Bound Bottom")
		(35 "F.Fab" user "Ref Des/Assembly Top")
		(33 "B.Fab" user "Ref Des/Assembly Bottom")
	)
	(footprint ""
		(layer "F.Cu")
		(at 16.690086 -10.729976 90)
		(property "Reference" "J14"
			(at 0.573024 -3.328416 90)
			(unlocked yes)
			(layer "F.SilkS")
			(effects
				(font
					(size 0.7874 0.5842)
					(thickness 0.1524)
				)
				(justify left)
			)
		)
		(property "Value" ""
			(at 0 0 90)
			(layer "F.Fab")
			(effects
				(font
					(size 1.27 1.27)
				)
			)
		)
		(duplicate_pad_numbers_are_jumpers no)
		(fp_line
			(start 3.81 -1.459992)
			(end 3.81 9.079992)
			(stroke
				(width 0.1524)
				(type default)
			)
			(layer "F.SilkS")
		)
		(fp_line
			(start -1.27 -1.459992)
			(end 3.81 -1.459992)
			(stroke
				(width 0.1524)
				(type default)
			)
			(layer "F.SilkS")
		)
		(fp_line
			(start 3.81 9.079992)
			(end -1.27 9.079992)
			(stroke
				(width 0.1524)
				(type default)
			)
			(layer "F.SilkS")
		)
		(fp_line
			(start -1.27 9.079992)
			(end -1.27 -1.459992)
			(stroke
				(width 0.1524)
				(type default)
			)
			(layer "F.SilkS")
		)
		(fp_poly
			(pts
				(xy -2.54 0.508) (xy -2.54 -0.508) (xy -1.524 0)
			)
			(stroke
				(width 0)
				(type default)
			)
			(fill yes)
			(layer "F.SilkS")
		)
		(fp_line
			(start 3.81 -1.459992)
			(end 3.81 9.079992)
			(stroke
				(width 0.1)
				(type default)
			)
			(layer "F.Fab")
		)
		(fp_line
			(start -1.27 -1.459992)
			(end 3.81 -1.459992)
			(stroke
				(width 0.1)
				(type default)
			)
			(layer "F.Fab")
		)
		(fp_line
			(start 3.81 9.079992)
			(end -1.27 9.079992)
			(stroke
				(width 0.1)
				(type default)
			)
			(layer "F.Fab")
		)
		(fp_line
			(start -1.27 9.079992)
			(end -1.27 -1.459992)
			(stroke
				(width 0.1)
				(type default)
			)
			(layer "F.Fab")
		)
		(fp_poly
			(pts
				(xy -2.54 0.508) (xy -2.54 -0.508) (xy -1.524 0)
			)
			(stroke
				(width 0)
				(type default)
			)
			(fill yes)
			(layer "F.Fab")
		)
		(fp_text user "2"
			(at 2.629154 -2.288286 0)
			(unlocked yes)
			(layer "F.SilkS")
			(effects
				(font
					(size 0.7874 0.5842)
					(thickness 0.1524)
				)
			)
		)
		(fp_text user "8"
			(at 4.48183 7.6073 0)
			(unlocked yes)
			(layer "F.SilkS")
			(effects
				(font
					(size 0.7874 0.5842)
					(thickness 0.1524)
				)
			)
		)
		(fp_text user "7"
			(at -1.908556 8.800592 0)
			(unlocked yes)
			(layer "F.SilkS")
			(effects
				(font
					(size 0.7874 0.5842)
					(thickness 0.1524)
				)
			)
		)
		(fp_text user "2"
			(at 2.56413 -1.1811 0)
			(unlocked yes)
			(layer "B.SilkS")
			(effects
				(font
					(size 0.7874 0.5842)
					(thickness 0.1524)
				)
				(justify mirror)
			)
		)
		(fp_text user "1"
			(at -0.05207 -1.1303 0)
			(unlocked yes)
			(layer "B.SilkS")
			(effects
				(font
					(size 0.7874 0.5842)
					(thickness 0.1524)
				)
				(justify mirror)
			)
		)
		(fp_text user "7"
			(at -0.01397 8.7249 0)
			(unlocked yes)
			(layer "B.SilkS")
			(effects
				(font
					(size 0.7874 0.5842)
					(thickness 0.1524)
				)
				(justify mirror)
			)
		)
		(fp_text user "8"
			(at 2.56413 8.7757 0)
			(unlocked yes)
			(layer "B.SilkS")
			(effects
				(font
					(size 0.7874 0.5842)
					(thickness 0.1524)
				)
				(justify mirror)
			)
		)
		(fp_text user "2"
			(at 2.56413 -1.1811 0)
			(unlocked yes)
			(layer "B.Fab")
			(effects
				(font
					(size 0.7874 0.5842)
					(thickness 0.1524)
				)
				(justify mirror)
			)
		)
		(fp_text user "1"
			(at -0.05207 -1.1303 0)
			(unlocked yes)
			(layer "B.Fab")
			(effects
				(font
					(size 0.7874 0.5842)
					(thickness 0.1524)
				)
				(justify mirror)
			)
		)
		(fp_text user "7"
			(at -0.01397 8.7249 0)
			(unlocked yes)
			(layer "B.Fab")
			(effects
				(font
					(size 0.7874 0.5842)
					(thickness 0.1524)
				)
				(justify mirror)
			)
		)
		(fp_text user "8"
			(at 2.56413 8.7757 0)
			(unlocked yes)
			(layer "B.Fab")
			(effects
				(font
					(size 0.7874 0.5842)
					(thickness 0.1524)
				)
				(justify mirror)
			)
		)
		(fp_text user "2"
			(at 4.48183 0 0)
			(unlocked yes)
			(layer "F.Fab")
			(effects
				(font
					(size 0.7874 0.5842)
					(thickness 0.1524)
				)
			)
		)
		(fp_text user "7"
			(at -2.07137 7.5565 0)
			(unlocked yes)
			(layer "F.Fab")
			(effects
				(font
					(size 0.7874 0.5842)
					(thickness 0.1524)
				)
			)
		)
		(fp_text user "8"
			(at 4.48183 7.6073 0)
			(unlocked yes)
			(layer "F.Fab")
			(effects
				(font
					(size 0.7874 0.5842)
					(thickness 0.1524)
				)
			)
		)
		(pad "1" thru_hole rect
			(at 0 0)
			(size 1.5494 1.5494)
			(drill 1.0414)
			(layers "*.Cu" "*.Mask")
			(remove_unused_layers no)
			(net "P3V3_AUX")
			(clearance 0)
			(padstack
				(mode front_inner_back)
				(layer "Inner"
					(shape circle)
					(size 1.5494 1.5494)
					(clearance 0)
				)
				(layer "B.Cu"
					(shape rect)
					(size 1.5494 1.5494)
					(clearance 0)
				)
			)
		)
		(pad "2" thru_hole circle
			(at 2.54 0)
			(size 1.5494 1.5494)
			(drill 1.0414)
			(layers "*.Cu" "*.Mask")
			(remove_unused_layers no)
			(net "SMB_TMP421_BMC_MM2_SDA")
			(clearance 0)
		)
		(pad "3" thru_hole circle
			(at 0 2.54)
			(size 1.5494 1.5494)
			(drill 1.0414)
			(layers "*.Cu" "*.Mask")
			(remove_unused_layers no)
			(net "TMC75_A0")
			(clearance 0)
		)
		(pad "4" thru_hole circle
			(at 2.54 2.54)
			(size 1.5494 1.5494)
			(drill 1.0414)
			(layers "*.Cu" "*.Mask")
			(remove_unused_layers no)
			(net "SMB_TMP421_BMC_MM2_SCL")
			(clearance 0)
		)
		(pad "5" thru_hole circle
			(at 0 5.08)
			(size 1.5494 1.5494)
			(drill 1.0414)
			(layers "*.Cu" "*.Mask")
			(remove_unused_layers no)
			(net "TMC75_A1")
			(clearance 0)
		)
		(pad "6" thru_hole circle
			(at 2.54 5.08)
			(size 1.5494 1.5494)
			(drill 1.0414)
			(layers "*.Cu" "*.Mask")
			(remove_unused_layers no)
			(net "SMB_BMC_ALERT16_R_N")
			(clearance 0)
		)
		(pad "7" thru_hole circle
			(at 0 7.62)
			(size 1.5494 1.5494)
			(drill 1.0414)
			(layers "*.Cu" "*.Mask")
			(remove_unused_layers no)
			(net "TMC75_A2")
			(clearance 0)
		)
		(pad "8" thru_hole circle
			(at 2.54 7.62)
			(size 1.5494 1.5494)
			(drill 1.0414)
			(layers "*.Cu" "*.Mask")
			(remove_unused_layers no)
			(net "GND")
			(clearance 0)
		)
	)
)
